(kicad_pcb
	(version 20241229)
	(generator "pcbnew")
	(generator_version "9.0")
	(general
		(thickness 1.6296)
		(legacy_teardrops no)
	)
	(paper "A3")
	(title_block
		(title "Thunderbolt to 10GbE adapter")
		(date "2026-04-21")
		(rev "1.1.0")
		(company "Antmicro Ltd")
		(comment 1 "www.antmicro.com")
		(comment 9 "footprints 621-624 of 703")
	)
	(layers
		(0 "F.Cu" signal)
		(4 "In1.Cu" signal)
		(6 "In2.Cu" signal)
		(8 "In3.Cu" signal)
		(10 "In4.Cu" signal)
		(12 "In5.Cu" signal)
		(14 "In6.Cu" signal)
		(2 "B.Cu" signal)
		(9 "F.Adhes" user "F.Adhesive")
		(11 "B.Adhes" user "B.Adhesive")
		(13 "F.Paste" user)
		(15 "B.Paste" user)
		(5 "F.SilkS" user "F.Silkscreen")
		(7 "B.SilkS" user "B.Silkscreen")
		(1 "F.Mask" user)
		(3 "B.Mask" user)
		(17 "Dwgs.User" user "User.Drawings")
		(19 "Cmts.User" user "User.Comments")
		(21 "Eco1.User" user "User.Eco1")
		(23 "Eco2.User" user "User.Eco2")
		(25 "Edge.Cuts" user)
		(27 "Margin" user)
		(31 "F.CrtYd" user "F.Courtyard")
		(29 "B.CrtYd" user "B.Courtyard")
		(35 "F.Fab" user)
		(33 "B.Fab" user)
	)
	(footprint "antmicro-footprints:C_0402_1005Metric"
		(layer "B.Cu")
		(at 145.631866 76.260117 180)
		(descr "Capacitor SMD 0402")
		(tags "capacitor SMD 0402")
		(property "Reference" "C235"
			(at -17.768134 -9.464883 0)
			(layer "B.SilkS")
			(effects
				(font
					(size 0.7 0.7)
					(thickness 0.15)
				)
				(justify mirror)
			)
		)
		(property "Value" "C_1u_25V_0402"
			(at -1.022927 -2.155213 0)
			(layer "B.Fab")
			(effects
				(font
					(size 0.7 0.7)
					(thickness 0.15)
				)
				(justify left bottom mirror)
			)
		)
		(property "Datasheet" "https://www.murata.com/products/productdetail?partno=GRM155R61E105KE11%23"
			(at 0 0 0)
			(layer "B.Fab")
			(hide yes)
			(effects
				(font
					(size 1.27 1.27)
					(thickness 0.15)
				)
				(justify mirror)
			)
		)
		(property "Description" "SMD Multilayer Ceramic Capacitor, 1 µF, 25 V, 0402 [1005 Metric], ± 10%, X5R, GRM Series"
			(at 0 0 0)
			(layer "B.Fab")
			(hide yes)
			(effects
				(font
					(size 1.27 1.27)
					(thickness 0.15)
				)
				(justify mirror)
			)
		)
		(property "MPN" "GRM155R61E105KE11J"
			(at 0 0 180)
			(unlocked yes)
			(layer "B.Fab")
			(hide yes)
			(effects
				(font
					(size 1 1)
					(thickness 0.15)
				)
				(justify mirror)
			)
		)
		(property "Manufacturer" "Murata"
			(at 0 0 180)
			(unlocked yes)
			(layer "B.Fab")
			(hide yes)
			(effects
				(font
					(size 1 1)
					(thickness 0.15)
				)
				(justify mirror)
			)
		)
		(property "License" "Apache-2.0"
			(at 0 0 180)
			(unlocked yes)
			(layer "B.Fab")
			(hide yes)
			(effects
				(font
					(size 1 1)
					(thickness 0.15)
				)
				(justify mirror)
			)
		)
		(property "Author" "Antmicro"
			(at 0 0 180)
			(unlocked yes)
			(layer "B.Fab")
			(hide yes)
			(effects
				(font
					(size 1 1)
					(thickness 0.15)
				)
				(justify mirror)
			)
		)
		(property "Val" "1u"
			(at 0 0 180)
			(unlocked yes)
			(layer "B.Fab")
			(hide yes)
			(effects
				(font
					(size 1 1)
					(thickness 0.15)
				)
				(justify mirror)
			)
		)
		(property "Voltage" "25V"
			(at 0 0 180)
			(unlocked yes)
			(layer "B.Fab")
			(hide yes)
			(effects
				(font
					(size 1 1)
					(thickness 0.15)
				)
				(justify mirror)
			)
		)
		(property "Dielectric" "X5R"
			(at 0 0 180)
			(unlocked yes)
			(layer "B.Fab")
			(hide yes)
			(effects
				(font
					(size 1 1)
					(thickness 0.15)
				)
				(justify mirror)
			)
		)
		(sheetname "/X710-AT2 power/")
		(sheetfile "x710-at2-power.kicad_sch")
		(attr smd)
		(fp_rect
			(start -0.925 0.47)
			(end 0.925 -0.47)
			(stroke
				(width 0.05)
				(type default)
			)
			(fill no)
			(layer "B.CrtYd")
		)
		(fp_line
			(start 0.504 0.25)
			(end 0.504 -0.248)
			(stroke
				(width 0.15)
				(type solid)
			)
			(layer "B.Fab")
		)
		(fp_line
			(start 0.504 -0.248)
			(end -0.494 -0.248)
			(stroke
				(width 0.15)
				(type solid)
			)
			(layer "B.Fab")
		)
		(fp_line
			(start -0.494 0.25)
			(end 0.504 0.25)
			(stroke
				(width 0.15)
				(type solid)
			)
			(layer "B.Fab")
		)
		(fp_line
			(start -0.494 -0.248)
			(end -0.494 0.25)
			(stroke
				(width 0.15)
				(type solid)
			)
			(layer "B.Fab")
		)
		(fp_text user "${REFERENCE}"
			(at -0.939 -4.599 0)
			(layer "B.Fab")
			(effects
				(font
					(size 0.7 0.7)
					(thickness 0.15)
				)
				(justify left bottom mirror)
			)
		)
		(fp_text user "License: Apache-2.0"
			(at -0.939 -5.799 0)
			(layer "B.Fab")
			(effects
				(font
					(size 0.7 0.7)
					(thickness 0.15)
				)
				(justify left bottom mirror)
			)
		)
		(fp_text user "Author: Antmicro"
			(at -0.939 -3.399 0)
			(layer "B.Fab")
			(effects
				(font
					(size 0.7 0.7)
					(thickness 0.15)
				)
				(justify left bottom mirror)
			)
		)
		(pad "1" smd roundrect
			(at -0.48 0 180)
			(size 0.59 0.64)
			(layers "B.Cu" "B.Mask" "B.Paste")
			(roundrect_rratio 0.25)
			(net 23 "GND")
			(pintype "passive")
		)
		(pad "2" smd roundrect
			(at 0.48 0 180)
			(size 0.59 0.64)
			(layers "B.Cu" "B.Mask" "B.Paste")
			(roundrect_rratio 0.25)
			(net 7 "+3V3")
			(pintype "passive")
		)
	)
	(footprint "antmicro-footprints:R_0402_1005Metric"
		(layer "B.Cu")
		(at 120.500001 89.749998 90)
		(descr "Resistor SMD 0402")
		(tags "resistor SMD 0402")
		(property "Reference" "R78"
			(at -5.85 0.3 270)
			(layer "B.SilkS")
			(effects
				(font
					(size 0.7 0.7)
					(thickness 0.15)
				)
				(justify left bottom mirror)
			)
		)
		(property "Value" "R_47k_0402"
			(at -1.011843 -1.772047 270)
			(layer "B.Fab")
			(effects
				(font
					(size 0.7 0.7)
					(thickness 0.15)
				)
				(justify left bottom mirror)
			)
		)
		(property "Datasheet" "https://www.bourns.com/docs/product-datasheets/cr.pdf"
			(at 0 0 270)
			(layer "B.Fab")
			(hide yes)
			(effects
				(font
					(size 1.27 1.27)
					(thickness 0.15)
				)
				(justify mirror)
			)
		)
		(property "Description" "SMD Chip Resistor, 47 kohm, ± 1%, 62.5 mW, 0402 [1005 Metric], Thick Film, General Purpose"
			(at 0 0 270)
			(layer "B.Fab")
			(hide yes)
			(effects
				(font
					(size 1.27 1.27)
					(thickness 0.15)
				)
				(justify mirror)
			)
		)
		(property "MPN" "CR0402-FX-4702GLF"
			(at 0 0 90)
			(unlocked yes)
			(layer "B.Fab")
			(hide yes)
			(effects
				(font
					(size 1 1)
					(thickness 0.15)
				)
				(justify mirror)
			)
		)
		(property "Manufacturer" "Bourns"
			(at 0 0 90)
			(unlocked yes)
			(layer "B.Fab")
			(hide yes)
			(effects
				(font
					(size 1 1)
					(thickness 0.15)
				)
				(justify mirror)
			)
		)
		(property "License" "Apache-2.0"
			(at 0 0 90)
			(unlocked yes)
			(layer "B.Fab")
			(hide yes)
			(effects
				(font
					(size 1 1)
					(thickness 0.15)
				)
				(justify mirror)
			)
		)
		(property "Author" "Antmicro"
			(at 0 0 90)
			(unlocked yes)
			(layer "B.Fab")
			(hide yes)
			(effects
				(font
					(size 1 1)
					(thickness 0.15)
				)
				(justify mirror)
			)
		)
		(property "Val" "47k"
			(at 0 0 90)
			(unlocked yes)
			(layer "B.Fab")
			(hide yes)
			(effects
				(font
					(size 1 1)
					(thickness 0.15)
				)
				(justify mirror)
			)
		)
		(property "Tolerance" "1%"
			(at 0 0 90)
			(unlocked yes)
			(layer "B.Fab")
			(hide yes)
			(effects
				(font
					(size 1 1)
					(thickness 0.15)
				)
				(justify mirror)
			)
		)
		(sheetname "/TB Controller - Power/")
		(sheetfile "tb-power.kicad_sch")
		(attr smd)
		(fp_rect
			(start -0.925 0.47)
			(end 0.925 -0.47)
			(stroke
				(width 0.05)
				(type default)
			)
			(fill no)
			(layer "B.CrtYd")
		)
		(fp_rect
			(start -0.5 0.25)
			(end 0.5 -0.25)
			(stroke
				(width 0.15)
				(type solid)
			)
			(fill no)
			(layer "B.Fab")
		)
		(fp_text user "License: Apache-2.0"
			(at -0.95 -5.169 270)
			(layer "B.Fab")
			(effects
				(font
					(size 0.7 0.7)
					(thickness 0.15)
				)
				(justify left bottom mirror)
			)
		)
		(fp_text user "${REFERENCE}"
			(at -0.95 -3.168 270)
			(layer "B.Fab")
			(effects
				(font
					(size 0.7 0.7)
					(thickness 0.15)
				)
				(justify left bottom mirror)
			)
		)
		(fp_text user "Author: Antmicro"
			(at -0.95 -4.169 270)
			(layer "B.Fab")
			(effects
				(font
					(size 0.7 0.7)
					(thickness 0.15)
				)
				(justify left bottom mirror)
			)
		)
		(pad "1" smd roundrect
			(at -0.48 0 90)
			(size 0.59 0.64)
			(layers "B.Cu" "B.Mask" "B.Paste")
			(roundrect_rratio 0.25)
			(net 436 "Net-(R77-Pad1)")
			(pintype "passive")
		)
		(pad "2" smd roundrect
			(at 0.48 0 90)
			(size 0.59 0.64)
			(layers "B.Cu" "B.Mask" "B.Paste")
			(roundrect_rratio 0.25)
			(net 356 "/TB Controller - Power/0P9_BUFFERED")
			(pintype "passive")
		)
	)
	(footprint "antmicro-footprints:C_Pol_EIA-A"
		(layer "B.Cu")
		(at 158.8 103 -90)
		(property "Reference" "C328"
			(at -5 -0.5 90)
			(layer "B.SilkS")
			(effects
				(font
					(size 0.7 0.7)
					(thickness 0.15)
				)
				(justify left bottom mirror)
			)
		)
		(property "Value" "C_Pol_100u_6V_KEMET-T490-A"
			(at 0 -2 90)
			(layer "B.Fab")
			(effects
				(font
					(size 0.7 0.7)
					(thickness 0.15)
				)
				(justify left bottom mirror)
			)
		)
		(property "Datasheet" "https://www.kemet.com/en/us/capacitors/product/T490A107M006ATE800.html"
			(at 0 0 90)
			(layer "B.Fab")
			(hide yes)
			(effects
				(font
					(size 1.27 1.27)
					(thickness 0.15)
				)
				(justify mirror)
			)
		)
		(property "Description" "Surface Mount Tantalum Capacitor,  Solid SMD 6V 100uF 1206 20% ESR=800mOhms"
			(at 0 0 90)
			(layer "B.Fab")
			(hide yes)
			(effects
				(font
					(size 1.27 1.27)
					(thickness 0.15)
				)
				(justify mirror)
			)
		)
		(property "Val" "100u"
			(at 0 0 270)
			(unlocked yes)
			(layer "B.Fab")
			(hide yes)
			(effects
				(font
					(size 1 1)
					(thickness 0.15)
				)
				(justify mirror)
			)
		)
		(property "MPN" "T490A107M006ATE800"
			(at 0 0 270)
			(unlocked yes)
			(layer "B.Fab")
			(hide yes)
			(effects
				(font
					(size 1 1)
					(thickness 0.15)
				)
				(justify mirror)
			)
		)
		(property "Manufacturer" "KEMET"
			(at 0 0 270)
			(unlocked yes)
			(layer "B.Fab")
			(hide yes)
			(effects
				(font
					(size 1 1)
					(thickness 0.15)
				)
				(justify mirror)
			)
		)
		(property "License" "Apache-2.0"
			(at 0 0 270)
			(unlocked yes)
			(layer "B.Fab")
			(hide yes)
			(effects
				(font
					(size 1 1)
					(thickness 0.15)
				)
				(justify mirror)
			)
		)
		(property "Author" "Antmicro"
			(at 0 0 270)
			(unlocked yes)
			(layer "B.Fab")
			(hide yes)
			(effects
				(font
					(size 1 1)
					(thickness 0.15)
				)
				(justify mirror)
			)
		)
		(property "Voltage" "6V"
			(at 0 0 270)
			(unlocked yes)
			(layer "B.Fab")
			(hide yes)
			(effects
				(font
					(size 1 1)
					(thickness 0.15)
				)
				(justify mirror)
			)
		)
		(property "Dielectric" "template_dielectric"
			(at 0 0 270)
			(unlocked yes)
			(layer "B.Fab")
			(hide yes)
			(effects
				(font
					(size 1 1)
					(thickness 0.15)
				)
				(justify mirror)
			)
		)
		(sheetname "/X710-AT2 power/")
		(sheetfile "x710-at2-power.kicad_sch")
		(attr smd)
		(fp_line
			(start -1.95 1.25)
			(end -1.95 0.95)
			(stroke
				(width 0.12)
				(type solid)
			)
			(layer "B.SilkS")
		)
		(fp_line
			(start -2.1 1.1)
			(end -1.8 1.1)
			(stroke
				(width 0.12)
				(type solid)
			)
			(layer "B.SilkS")
		)
		(fp_line
			(start -1.5 0.85)
			(end 1.5 0.85)
			(stroke
				(width 0.12)
				(type solid)
			)
			(layer "B.SilkS")
		)
		(fp_line
			(start -1.5 0.75)
			(end -1.5 0.85)
			(stroke
				(width 0.12)
				(type solid)
			)
			(layer "B.SilkS")
		)
		(fp_line
			(start 1.5 0.75)
			(end 1.5 0.85)
			(stroke
				(width 0.12)
				(type solid)
			)
			(layer "B.SilkS")
		)
		(fp_line
			(start -1.5 -0.75)
			(end -1.5 -0.85)
			(stroke
				(width 0.12)
				(type solid)
			)
			(layer "B.SilkS")
		)
		(fp_line
			(start 1.5 -0.75)
			(end 1.5 -0.85)
			(stroke
				(width 0.12)
				(type solid)
			)
			(layer "B.SilkS")
		)
		(fp_line
			(start 1.5 -0.85)
			(end -1.5 -0.85)
			(stroke
				(width 0.12)
				(type solid)
			)
			(layer "B.SilkS")
		)
		(fp_line
			(start 1.7 1.05)
			(end -1.7 1.05)
			(stroke
				(width 0.05)
				(type solid)
			)
			(layer "B.CrtYd")
		)
		(fp_line
			(start -2.05 0.85)
			(end -2.05 -0.85)
			(stroke
				(width 0.05)
				(type solid)
			)
			(layer "B.CrtYd")
		)
		(fp_line
			(start -1.7 0.85)
			(end -1.7 1.05)
			(stroke
				(width 0.05)
				(type solid)
			)
			(layer "B.CrtYd")
		)
		(fp_line
			(start -1.7 0.85)
			(end -2.05 0.85)
			(stroke
				(width 0.05)
				(type solid)
			)
			(layer "B.CrtYd")
		)
		(fp_line
			(start 1.7 0.85)
			(end 1.7 1.05)
			(stroke
				(width 0.05)
				(type solid)
			)
			(layer "B.CrtYd")
		)
		(fp_line
			(start 2.05 0.85)
			(end 1.7 0.85)
			(stroke
				(width 0.05)
				(type solid)
			)
			(layer "B.CrtYd")
		)
		(fp_line
			(start 2.05 0.85)
			(end 2.05 -0.85)
			(stroke
				(width 0.05)
				(type solid)
			)
			(layer "B.CrtYd")
		)
		(fp_line
			(start -1.7 -0.85)
			(end -2.05 -0.85)
			(stroke
				(width 0.05)
				(type solid)
			)
			(layer "B.CrtYd")
		)
		(fp_line
			(start 2.05 -0.85)
			(end 1.7 -0.85)
			(stroke
				(width 0.05)
				(type solid)
			)
			(layer "B.CrtYd")
		)
		(fp_line
			(start -1.7 -1.05)
			(end -1.7 -0.85)
			(stroke
				(width 0.05)
				(type solid)
			)
			(layer "B.CrtYd")
		)
		(fp_line
			(start 1.7 -1.05)
			(end 1.7 -0.85)
			(stroke
				(width 0.05)
				(type solid)
			)
			(layer "B.CrtYd")
		)
		(fp_line
			(start 1.7 -1.05)
			(end -1.7 -1.05)
			(stroke
				(width 0.05)
				(type solid)
			)
			(layer "B.CrtYd")
		)
		(fp_rect
			(start -1.601 0.802)
			(end 1.6 -0.8)
			(stroke
				(width 0.1)
				(type solid)
			)
			(fill no)
			(layer "B.Fab")
		)
		(fp_text user "${REFERENCE}"
			(at -2.1 -4.198 90)
			(layer "B.Fab")
			(effects
				(font
					(size 0.7 0.7)
					(thickness 0.15)
				)
				(justify left bottom mirror)
			)
		)
		(fp_text user "License: Apache-2.0"
			(at -2.1 -5.198 90)
			(layer "B.Fab")
			(effects
				(font
					(size 0.7 0.7)
					(thickness 0.15)
				)
				(justify left bottom mirror)
			)
		)
		(fp_text user "Author: Antmicro"
			(at -2.1 -6.198 90)
			(layer "B.Fab")
			(effects
				(font
					(size 0.7 0.7)
					(thickness 0.15)
				)
				(justify left bottom mirror)
			)
		)
		(pad "1" smd roundrect
			(at -1.2 0 270)
			(size 1.2 1.2)
			(layers "B.Cu" "B.Mask" "B.Paste")
			(roundrect_rratio 0.1)
			(net 136 "+1V0")
			(pintype "passive")
		)
		(pad "2" smd roundrect
			(at 1.2 0 270)
			(size 1.2 1.2)
			(layers "B.Cu" "B.Mask" "B.Paste")
			(roundrect_rratio 0.1)
			(net 23 "GND")
			(pintype "passive")
		)
	)
	(footprint "antmicro-footprints:C_0402_1005Metric"
		(layer "B.Cu")
		(at 133.739999 116 180)
		(descr "Capacitor SMD 0402")
		(tags "capacitor SMD 0402")
		(property "Reference" "C35"
			(at -19.525001 7.450001 0)
			(layer "B.SilkS")
			(effects
				(font
					(size 0.7 0.7)
					(thickness 0.15)
				)
				(justify mirror)
			)
		)
		(property "Value" "C_100n_0402"
			(at -1.022927 -2.155213 0)
			(layer "B.Fab")
			(effects
				(font
					(size 0.7 0.7)
					(thickness 0.15)
				)
				(justify left bottom mirror)
			)
		)
		(property "Datasheet" "https://www.murata.com/products/productdetail?partno=GRM155R61H104KE14%23"
			(at 0 0 0)
			(layer "B.Fab")
			(hide yes)
			(effects
				(font
					(size 1.27 1.27)
					(thickness 0.15)
				)
				(justify mirror)
			)
		)
		(property "Description" "SMD Multilayer Ceramic Capacitor, 0.1 µF, 50 V, 0402 [1005 Metric], ± 10%, X5R, GRM Series"
			(at 0 0 0)
			(layer "B.Fab")
			(hide yes)
			(effects
				(font
					(size 1.27 1.27)
					(thickness 0.15)
				)
				(justify mirror)
			)
		)
		(property "MPN" "GRM155R61H104KE14D"
			(at 0 0 180)
			(unlocked yes)
			(layer "B.Fab")
			(hide yes)
			(effects
				(font
					(size 1 1)
					(thickness 0.15)
				)
				(justify mirror)
			)
		)
		(property "Manufacturer" "Murata"
			(at 0 0 180)
			(unlocked yes)
			(layer "B.Fab")
			(hide yes)
			(effects
				(font
					(size 1 1)
					(thickness 0.15)
				)
				(justify mirror)
			)
		)
		(property "License" "Apache-2.0"
			(at 0 0 180)
			(unlocked yes)
			(layer "B.Fab")
			(hide yes)
			(effects
				(font
					(size 1 1)
					(thickness 0.15)
				)
				(justify mirror)
			)
		)
		(property "Val" "100n"
			(at 0 0 180)
			(unlocked yes)
			(layer "B.Fab")
			(hide yes)
			(effects
				(font
					(size 1 1)
					(thickness 0.15)
				)
				(justify mirror)
			)
		)
		(property "Voltage" "50V"
			(at 0 0 180)
			(unlocked yes)
			(layer "B.Fab")
			(hide yes)
			(effects
				(font
					(size 1 1)
					(thickness 0.15)
				)
				(justify mirror)
			)
		)
		(property "Dielectric" "X5R"
			(at 0 0 180)
			(unlocked yes)
			(layer "B.Fab")
			(hide yes)
			(effects
				(font
					(size 1 1)
					(thickness 0.15)
				)
				(justify mirror)
			)
		)
		(property "Author" "Antmicro"
			(at 0 0 180)
			(unlocked yes)
			(layer "B.Fab")
			(hide yes)
			(effects
				(font
					(size 1 1)
					(thickness 0.15)
				)
				(justify mirror)
			)
		)
		(sheetname "/TB Controller/")
		(sheetfile "tb.kicad_sch")
		(attr smd)
		(fp_rect
			(start -0.925 0.47)
			(end 0.925 -0.47)
			(stroke
				(width 0.05)
				(type default)
			)
			(fill no)
			(layer "B.CrtYd")
		)
		(fp_line
			(start 0.504 0.25)
			(end 0.504 -0.248)
			(stroke
				(width 0.15)
				(type solid)
			)
			(layer "B.Fab")
		)
		(fp_line
			(start 0.504 -0.248)
			(end -0.494 -0.248)
			(stroke
				(width 0.15)
				(type solid)
			)
			(layer "B.Fab")
		)
		(fp_line
			(start -0.494 0.25)
			(end 0.504 0.25)
			(stroke
				(width 0.15)
				(type solid)
			)
			(layer "B.Fab")
		)
		(fp_line
			(start -0.494 -0.248)
			(end -0.494 0.25)
			(stroke
				(width 0.15)
				(type solid)
			)
			(layer "B.Fab")
		)
		(fp_text user "Author: Antmicro"
			(at -0.939 -3.399 0)
			(layer "B.Fab")
			(effects
				(font
					(size 0.7 0.7)
					(thickness 0.15)
				)
				(justify left bottom mirror)
			)
		)
		(fp_text user "License: Apache-2.0"
			(at -0.939 -5.799 0)
			(layer "B.Fab")
			(effects
				(font
					(size 0.7 0.7)
					(thickness 0.15)
				)
				(justify left bottom mirror)
			)
		)
		(fp_text user "${REFERENCE}"
			(at -0.939 -4.599 0)
			(layer "B.Fab")
			(effects
				(font
					(size 0.7 0.7)
					(thickness 0.15)
				)
				(justify left bottom mirror)
			)
		)
		(pad "1" smd roundrect
			(at -0.48 0 180)
			(size 0.59 0.64)
			(layers "B.Cu" "B.Mask" "B.Paste")
			(roundrect_rratio 0.25)
			(net 69 "/PD and TB DC-DC/AUX.+")
			(pintype "passive")
		)
		(pad "2" smd roundrect
			(at 0.48 0 180)
			(size 0.59 0.64)
			(layers "B.Cu" "B.Mask" "B.Paste")
			(roundrect_rratio 0.25)
			(net 239 "/TB Controller/PA_AUX_P")
			(pintype "passive")
		)
	)
)
